# S9S_MB_2U (Grand Teton) — schematic netlist excerpt (pin names and nets, part order shuffled) for the footprints in the layout excerpt that follows; sources: Cadence DE-HDL packaged netlist, KiCad conversion of 03242023_DA0F0TMBIJ0_F0T_Motherboard_J_brd_V01_OCP.brd

J28  SCONN288_ADR50017P087CC  SCONN288_ADR50017-P087CC IO  pkg DDR288S_1-1VXB  page 109
  VIN_BULK0  = P12V_S3_AUX_CPU1_NVDIMM
  RFU0  = TP_CHF_CPU1_DIMM2_FRU_0
  VIN_MGMT  = P3V3_AUX
  HSCL  = I3C_SPD_DDREFGH_CPU1_LVC1_SCL_3
  HSDA  = I3C_SPD_DDREFGH_CPU1_LVC1_SDA
  VSS0  = GND
  DQ0_A  = M_F_CPU1_SA_DQ<0>
  VSS1  = GND
  DQ1_A  = M_F_CPU1_SA_DQ<1>
  VSS2  = GND
  DQS0_A_T  = M_F_CPU1_SA_DQS_DP<0>
  DQS0_A_C  = M_F_CPU1_SA_DQS_DN<0>
  VSS3  = GND
  DQ4_A  = M_F_CPU1_SA_DQ<4>
  VSS4  = GND
  DQ5_A  = M_F_CPU1_SA_DQ<5>
  VSS5  = GND
  DQ8_A  = M_F_CPU1_SA_DQ<8>
  VSS6  = GND
  DQ9_A  = M_F_CPU1_SA_DQ<9>
  VSS7  = GND
  DQS1_A_T  = M_F_CPU1_SA_DQS_DP<1>
  DQS1_A_C  = M_F_CPU1_SA_DQS_DN<1>
  VSS8  = GND
  DQ12_A  = M_F_CPU1_SA_DQ<12>
  VSS9  = GND
  DQ13_A  = M_F_CPU1_SA_DQ<13>
  VSS10  = GND
  DQ16_A  = M_F_CPU1_SA_DQ<16>
  VSS11  = GND
  DQ17_A  = M_F_CPU1_SA_DQ<17>
  VSS12  = GND
  DQS2_A_T  = M_F_CPU1_SA_DQS_DP<2>
  DQS2_A_C  = M_F_CPU1_SA_DQS_DN<2>
  VSS13  = GND
  DQ20_A  = M_F_CPU1_SA_DQ<20>
  VSS14  = GND
  DQ21_A  = M_F_CPU1_SA_DQ<21>
  VSS15  = GND
  DQ24_A  = M_F_CPU1_SA_DQ<24>
  VSS16  = GND
  DQ25_A  = M_F_CPU1_SA_DQ<25>
  VSS17  = GND
  DQS3_A_T  = M_F_CPU1_SA_DQS_DP<3>
  DQS3_A_C  = M_F_CPU1_SA_DQS_DN<3>
  VSS18  = GND
  DQ28_A  = M_F_CPU1_SA_DQ<28>
  VSS19  = GND
  DQ29_A  = M_F_CPU1_SA_DQ<29>
  VSS20  = GND
  CB0_A  = M_F_CPU1_SA_CB<0>
  VSS21  = GND
  CB1_A  = M_F_CPU1_SA_CB<1>
  VSS22  = GND
  DQS4_A_T  = M_F_CPU1_SA_DQS_DP<4>
  DQS4_A_C  = M_F_CPU1_SA_DQS_DN<4>
  VSS23  = GND
  CB4_A  = M_F_CPU1_SA_CB<4>
  VSS24  = GND
  CB5_A  = M_F_CPU1_SA_CB<5>
  VSS25  = GND
  ALERT_N  = M_F_CPU1_ALERT_N
  VSS26  = GND
  CS0_A_N  = M_F_CPU1_SA_CS_N<2>
  VSS27  = GND
  CA0_A  = M_F_CPU1_SA_CA<0>
  VSS28  = GND
  CA2_A  = M_F_CPU1_SA_CA<2>
  VSS29  = GND
  CA4_A  = M_F_CPU1_SA_CA<4>
  VSS30  = GND
  CA6_A  = M_F_CPU1_SA_CA<6>
  VSS31  = GND
  PAR_A  = M_F_CPU1_SA_PAR
  VSS32  = GND
  CA0_B  = M_F_CPU1_SB_CA<0>
  VSS33  = GND
  CA2_B  = M_F_CPU1_SB_CA<2>
  VSS34  = GND
  CA4_B  = M_F_CPU1_SB_CA<4>
  VSS35  = GND
  CA6_B  = M_F_CPU1_SB_CA<6>
  VSS36  = GND
  CS0_B_N  = M_F_CPU1_SB_CS_N<2>
  VSS37  = GND
  \lbd||rsp_a_n\  = M_F_CPU1_SA_RSP<1>
  \lbs||rsp_b_n\  = M_F_CPU1_SB_RSP<1>
  VSS38  = GND
  CB4_B  = M_F_CPU1_SB_CB<4>
  VSS39  = GND
  CB5_B  = M_F_CPU1_SB_CB<5>
  VSS40  = GND
  \dqs9_b_t||tdqs9_b_t||dbi4_b_n\  = M_F_CPU1_SB_DQS_DP<9>
  \dqs9_b_c||tdqs9_b_c\  = M_F_CPU1_SB_DQS_DN<9>
  VSS41  = GND
  CB0_B  = M_F_CPU1_SB_CB<0>
  VSS42  = GND
  CB1_B  = M_F_CPU1_SB_CB<1>
  VSS43  = GND
  DQ0_B  = M_F_CPU1_SB_DQ<0>
  VSS44  = GND
  DQ1_B  = M_F_CPU1_SB_DQ<1>
  VSS45  = GND
  DQS0_B_T  = M_F_CPU1_SB_DQS_DP<0>
  DQS0_B_C  = M_F_CPU1_SB_DQS_DN<0>
  VSS46  = GND
  DQ4_B  = M_F_CPU1_SB_DQ<4>
  VSS47  = GND
  DQ5_B  = M_F_CPU1_SB_DQ<5>
  VSS48  = GND
  DQ8_B  = M_F_CPU1_SB_DQ<8>
  VSS49  = GND
  DQ9_B  = M_F_CPU1_SB_DQ<9>
  VSS50  = GND
  DQS1_B_T  = M_F_CPU1_SB_DQS_DP<1>
  DQS1_B_C  = M_F_CPU1_SB_DQS_DN<1>
  VSS51  = GND
  DQ12_B  = M_F_CPU1_SB_DQ<12>
  VSS52  = GND
  DQ13_B  = M_F_CPU1_SB_DQ<13>
  VSS53  = GND
  DQ16_B  = M_F_CPU1_SB_DQ<16>
  VSS54  = GND
  DQ17_B  = M_F_CPU1_SB_DQ<17>
  VSS55  = GND
  DQS2_B_T  = M_F_CPU1_SB_DQS_DP<2>
  DQS2_B_C  = M_F_CPU1_SB_DQS_DN<2>
  VSS56  = GND
  DQ20_B  = M_F_CPU1_SB_DQ<20>
  VSS57  = GND
  DQ21_B  = M_F_CPU1_SB_DQ<21>
  VSS58  = GND
  DQ24_B  = M_F_CPU1_SB_DQ<24>
  VSS59  = GND
  DQ25_B  = M_F_CPU1_SB_DQ<25>
  VSS60  = GND
  DQS3_B_T  = M_F_CPU1_SB_DQS_DP<3>
  DQS3_B_C  = M_F_CPU1_SB_DQS_DN<3>
  VSS61  = GND
  DQ28_B  = M_F_CPU1_SB_DQ<28>
  VSS62  = GND
  DQ29_B  = M_F_CPU1_SB_DQ<29>
  VSS63  = GND
  RFU1  = TP_CHF_CPU1_DIMM2_FRU_1
  VIN_BULK1  = P12V_S3_AUX_CPU1_NVDIMM
  VIN_BULK2  = P12V_S3_AUX_CPU1_NVDIMM
  \pwr_good||fail_n\  = PWRGD_CHF_CPU1_DIMM2
  HSA  = PD_CHF_CPU1_DIMM2_SAA
  RFU2  = TP_CHF_CPU1_DIMM2_FRU_2
  RFU3  = TP_CHF_CPU1_DIMM2_FRU_3
  VSS64  = GND
  DQ2_A  = M_F_CPU1_SA_DQ<2>
  VSS65  = GND
  DQ3_A  = M_F_CPU1_SA_DQ<3>
  VSS66  = GND
  \dqs5_a_c||tdqs5_a_c||dqs5_a_t||tdqs5_a_t\  = M_F_CPU1_SA_DQS_DN<5>
  \dqs5_a_t||tdqs5_a_t\  = M_F_CPU1_SA_DQS_DP<5>
  VSS67  = GND
  DQ6_A  = M_F_CPU1_SA_DQ<6>
  VSS68  = GND
  DQ7_A  = M_F_CPU1_SA_DQ<7>
  VSS69  = GND
  DQ10_A  = M_F_CPU1_SA_DQ<10>
  VSS70  = GND
  DQ11_A  = M_F_CPU1_SA_DQ<11>
  VSS71  = GND
  \dqs6_a_c||tdqs6_a_c||dqs6_a_t||tdqs6_a_t\  = M_F_CPU1_SA_DQS_DN<6>
  \dqs6_a_t||tdqs6_a_t\  = M_F_CPU1_SA_DQS_DP<6>
  VSS72  = GND
  DQ14_A  = M_F_CPU1_SA_DQ<14>
  VSS73  = GND
  DQ15_A  = M_F_CPU1_SA_DQ<15>
  VSS74  = GND
  DQ18_A  = M_F_CPU1_SA_DQ<18>
  VSS75  = GND
  DQ19_A  = M_F_CPU1_SA_DQ<19>
  VSS76  = GND
  \dqs7_a_c||tdqs7_a_c\  = M_F_CPU1_SA_DQS_DN<7>
  \dqs7_a_t||tdqs7_a_t\  = M_F_CPU1_SA_DQS_DP<7>
  VSS77  = GND
  DQ22_A  = M_F_CPU1_SA_DQ<22>
  VSS78  = GND
  DQ23_A  = M_F_CPU1_SA_DQ<23>
  VSS79  = GND
  DQ26_A  = M_F_CPU1_SA_DQ<26>
  VSS80  = GND
  DQ27_A  = M_F_CPU1_SA_DQ<27>
  VSS81  = GND
  \dqs8_a_c||tdqs8_a_c\  = M_F_CPU1_SA_DQS_DN<8>
  \dqs8_a_t||tdqs8_a_t\  = M_F_CPU1_SA_DQS_DP<8>
  VSS82  = GND
  DQ30_A  = M_F_CPU1_SA_DQ<30>
  VSS83  = GND
  DQ31_A  = M_F_CPU1_SA_DQ<31>
  VSS84  = GND
  CB2_A  = M_F_CPU1_SA_CB<2>
  VSS85  = GND
  CB3_A  = M_F_CPU1_SA_CB<3>
  VSS86  = GND
  \dqs9_a_c||tdqs9_a_c\  = M_F_CPU1_SA_DQS_DN<9>
  \dqs9_a_t||tdqs9_a_t\  = M_F_CPU1_SA_DQS_DP<9>
  VSS87  = GND
  CB6_A  = M_F_CPU1_SA_CB<6>
  VSS88  = GND
  CB7_A  = M_F_CPU1_SA_CB<7>
  VSS89  = GND
  RESET_N  = RST_M_EF_CPU1_FPGA_N
  VSS90  = GND
  CS1_A_N  = M_F_CPU1_SA_CS_N<3>
  VSS91  = GND
  CA1_A  = M_F_CPU1_SA_CA<1>
  VSS92  = GND
  CA3_A  = M_F_CPU1_SA_CA<3>
  VSS93  = GND
  CA5_A  = M_F_CPU1_SA_CA<5>
  VSS94  = GND
  CK_T  = M_F_CPU1_CLK_DP<1>
  CK_C  = M_F_CPU1_CLK_DN<1>
  VSS95  = GND
  RFU4  = TP_CHF_CPU1_DIMM2_FRU_4
  CA1_B  = M_F_CPU1_SB_CA<1>
  VSS96  = GND
  CA3_B  = M_F_CPU1_SB_CA<3>
  VSS97  = GND
  CA5_B  = M_F_CPU1_SB_CA<5>
  VSS98  = GND
  PAR_B  = M_F_CPU1_SB_PAR
  VSS99  = GND
  CS1_B_N  = M_F_CPU1_SB_CS_N<3>
  VSS100  = GND
  RFU5  = TP_CHF_CPU1_DIMM2_FRU_5
  RFU6  = TP_CHF_CPU1_DIMM2_FRU_6
  VSS101  = GND
  CB6_B  = M_F_CPU1_SB_CB<6>
  VSS102  = GND
  CB7_B  = M_F_CPU1_SB_CB<7>
  VSS103  = GND
  DQS4_B_C  = M_F_CPU1_SB_DQS_DN<4>
  DQS4_B_T  = M_F_CPU1_SB_DQS_DP<4>
  VSS104  = GND
  CB2_B  = M_F_CPU1_SB_CB<2>
  VSS105  = GND
  CB3_B  = M_F_CPU1_SB_CB<3>
  VSS106  = GND
  DQ2_B  = M_F_CPU1_SB_DQ<2>
  VSS107  = GND
  DQ3_B  = M_F_CPU1_SB_DQ<3>
  VSS108  = GND
  \dqs5_b_c||tdqs5_b_c\  = M_F_CPU1_SB_DQS_DN<5>
  \dqs5_b_t||tdqs5_b_t\  = M_F_CPU1_SB_DQS_DP<5>
  VSS109  = GND
  DQ6_B  = M_F_CPU1_SB_DQ<6>
  VSS110  = GND
  DQ7_B  = M_F_CPU1_SB_DQ<7>
  VSS111  = GND
  DQ10_B  = M_F_CPU1_SB_DQ<10>
  VSS112  = GND
  DQ11_B  = M_F_CPU1_SB_DQ<11>
  VSS113  = GND
  \dqs6_b_c||tdqs6_b_c\  = M_F_CPU1_SB_DQS_DN<6>
  \dqs6_b_t||tdqs6_b_t\  = M_F_CPU1_SB_DQS_DP<6>
  VSS114  = GND
  DQ14_B  = M_F_CPU1_SB_DQ<14>
  VSS115  = GND
  DQ15_B  = M_F_CPU1_SB_DQ<15>
  VSS116  = GND
  DQ18_B  = M_F_CPU1_SB_DQ<18>
  VSS117  = GND
  DQ19_B  = M_F_CPU1_SB_DQ<19>
  VSS118  = GND
  \dqs7_b_c||tdqs7_b_c\  = M_F_CPU1_SB_DQS_DN<7>
  \dqs7_b_t||tdqs7_b_t\  = M_F_CPU1_SB_DQS_DP<7>
  VSS119  = GND
  DQ22_B  = M_F_CPU1_SB_DQ<22>
  VSS120  = GND
  DQ23_B  = M_F_CPU1_SB_DQ<23>
  VSS121  = GND
  DQ26_B  = M_F_CPU1_SB_DQ<26>
  VSS122  = GND
  DQ27_B  = M_F_CPU1_SB_DQ<27>
  VSS123  = GND
  \dqs8_b_c||tdqs8_b_c\  = M_F_CPU1_SB_DQS_DN<8>
  \dqs8_b_t||tdqs8_b_t\  = M_F_CPU1_SB_DQS_DP<8>
  VSS124  = GND
  DQ30_B  = M_F_CPU1_SB_DQ<30>
  VSS125  = GND
  DQ31_B  = M_F_CPU1_SB_DQ<31>
  VSS126  = GND
  G1  = GND
  G2  = GND
  G3  = GND

(kicad_pcb
	(version 20260206)
	(generator "pcbnew")
	(generator_version "10.0")
	(general
		(thickness 1.6)
		(legacy_teardrops no)
	)
	(paper "A4")
	(title_block
		(title "03242023_DA0F0TMBIJ0_F0T_Motherboard_J_brd_V01_OCP.brd")
		(comment 1 "Grand Teton / footprint 3431 of 6105 (J28), pads 92-137 of 291")
	)
	(layers
		(0 "F.Cu" signal "TOP")
		(4 "In1.Cu" signal "GND")
		(6 "In2.Cu" signal "IN1")
		(8 "In3.Cu" signal "GND1")
		(10 "In4.Cu" signal "IN2")
		(12 "In5.Cu" signal "GND2")
		(14 "In6.Cu" signal "IN3")
		(16 "In7.Cu" signal "GND3")
		(18 "In8.Cu" signal "VCC")
		(20 "In9.Cu" signal "VCC1")
		(22 "In10.Cu" signal "GND4")
		(24 "In11.Cu" signal "IN4")
		(26 "In12.Cu" signal "GND5")
		(28 "In13.Cu" signal "IN5")
		(30 "In14.Cu" signal "GND6")
		(32 "In15.Cu" signal "IN6")
		(34 "In16.Cu" signal "GND7")
		(2 "B.Cu" signal "BOTTOM")
		(9 "F.Adhes" user "F.Adhesive")
		(11 "B.Adhes" user "B.Adhesive")
		(13 "F.Paste" user "Package Geometry/Pastemask Top")
		(15 "B.Paste" user "Package Geometry/Pastemask Bottom")
		(5 "F.SilkS" user "Ref Des/Silkscreen Top")
		(7 "B.SilkS" user "Ref Des/Silkscreen Bottom")
		(1 "F.Mask" user "Board Geometry/Soldermask Top")
		(3 "B.Mask" user "Board Geometry/Soldermask Bottom")
		(17 "Dwgs.User" user "User.Drawings")
		(19 "Cmts.User" user "User.Comments")
		(21 "Eco1.User" user "User.Eco1")
		(23 "Eco2.User" user "User.Eco2")
		(25 "Edge.Cuts" user "Board Geometry/Outline")
		(27 "Margin" user)
		(31 "F.CrtYd" user "Package Geometry/Place Bound Top")
		(29 "B.CrtYd" user "Package Geometry/Place Bound Bottom")
		(35 "F.Fab" user "Ref Des/Assembly Top")
		(33 "B.Fab" user "Ref Des/Assembly Bottom")
	)
	(footprint ""
		(layer "F.Cu")
		(at 175.95088 -258.091686)
		(property "Reference" "J28"
			(at -0.26924 -81.680812 0)
			(unlocked yes)
			(layer "F.SilkS")
			(effects
				(font
					(size 0.7874 0.5842)
					(thickness 0.1524)
				)
				(justify left)
			)
		)
		(property "Value" ""
			(at 0 0 0)
			(layer "F.Fab")
			(effects
				(font
					(size 1.27 1.27)
				)
			)
		)
		(duplicate_pad_numbers_are_jumpers no)
		(pad "92" smd rect
			(at -2.050034 19.12493 270)
			(size 0.519938 1.4986)
			(layers "F.Cu" "F.Mask" "F.Paste")
			(net "GND")
		)
		(pad "93" smd rect
			(at -2.050034 19.975068 270)
			(size 0.519938 1.4986)
			(layers "F.Cu" "F.Mask" "F.Paste")
			(net "M_F_CPU1_SB_DQS_DP<9>")
		)
		(pad "94" smd rect
			(at -2.050034 20.824952 270)
			(size 0.519938 1.4986)
			(layers "F.Cu" "F.Mask" "F.Paste")
			(net "M_F_CPU1_SB_DQS_DN<9>")
		)
		(pad "95" smd rect
			(at -2.050034 21.67509 270)
			(size 0.519938 1.4986)
			(layers "F.Cu" "F.Mask" "F.Paste")
			(net "GND")
		)
		(pad "96" smd rect
			(at -2.050034 22.524974 270)
			(size 0.519938 1.4986)
			(layers "F.Cu" "F.Mask" "F.Paste")
			(net "M_F_CPU1_SB_CB<0>")
		)
		(pad "97" smd rect
			(at -2.050034 23.375112 270)
			(size 0.519938 1.4986)
			(layers "F.Cu" "F.Mask" "F.Paste")
			(net "GND")
		)
		(pad "98" smd rect
			(at -2.050034 24.224996 270)
			(size 0.519938 1.4986)
			(layers "F.Cu" "F.Mask" "F.Paste")
			(net "M_F_CPU1_SB_CB<1>")
		)
		(pad "99" smd rect
			(at -2.050034 25.07488 270)
			(size 0.519938 1.4986)
			(layers "F.Cu" "F.Mask" "F.Paste")
			(net "GND")
		)
		(pad "100" smd rect
			(at -2.050034 25.925018 270)
			(size 0.519938 1.4986)
			(layers "F.Cu" "F.Mask" "F.Paste")
			(net "M_F_CPU1_SB_DQ<0>")
		)
		(pad "101" smd rect
			(at -2.050034 26.774902 270)
			(size 0.519938 1.4986)
			(layers "F.Cu" "F.Mask" "F.Paste")
			(net "GND")
		)
		(pad "102" smd rect
			(at -2.050034 27.62504 270)
			(size 0.519938 1.4986)
			(layers "F.Cu" "F.Mask" "F.Paste")
			(net "M_F_CPU1_SB_DQ<1>")
		)
		(pad "103" smd rect
			(at -2.050034 28.474924 270)
			(size 0.519938 1.4986)
			(layers "F.Cu" "F.Mask" "F.Paste")
			(net "GND")
		)
		(pad "104" smd rect
			(at -2.050034 29.325062 270)
			(size 0.519938 1.4986)
			(layers "F.Cu" "F.Mask" "F.Paste")
			(net "M_F_CPU1_SB_DQS_DP<0>")
		)
		(pad "105" smd rect
			(at -2.050034 30.174946 270)
			(size 0.519938 1.4986)
			(layers "F.Cu" "F.Mask" "F.Paste")
			(net "M_F_CPU1_SB_DQS_DN<0>")
		)
		(pad "106" smd rect
			(at -2.050034 31.025084 270)
			(size 0.519938 1.4986)
			(layers "F.Cu" "F.Mask" "F.Paste")
			(net "GND")
		)
		(pad "107" smd rect
			(at -2.050034 31.874968 270)
			(size 0.519938 1.4986)
			(layers "F.Cu" "F.Mask" "F.Paste")
			(net "M_F_CPU1_SB_DQ<4>")
		)
		(pad "108" smd rect
			(at -2.050034 32.725106 270)
			(size 0.519938 1.4986)
			(layers "F.Cu" "F.Mask" "F.Paste")
			(net "GND")
		)
		(pad "109" smd rect
			(at -2.050034 33.57499 270)
			(size 0.519938 1.4986)
			(layers "F.Cu" "F.Mask" "F.Paste")
			(net "M_F_CPU1_SB_DQ<5>")
		)
		(pad "110" smd rect
			(at -2.050034 34.425128 270)
			(size 0.519938 1.4986)
			(layers "F.Cu" "F.Mask" "F.Paste")
			(net "GND")
		)
		(pad "111" smd rect
			(at -2.050034 35.275012 270)
			(size 0.519938 1.4986)
			(layers "F.Cu" "F.Mask" "F.Paste")
			(net "M_F_CPU1_SB_DQ<8>")
		)
		(pad "112" smd rect
			(at -2.050034 36.124896 270)
			(size 0.519938 1.4986)
			(layers "F.Cu" "F.Mask" "F.Paste")
			(net "GND")
		)
		(pad "113" smd rect
			(at -2.050034 36.975034 270)
			(size 0.519938 1.4986)
			(layers "F.Cu" "F.Mask" "F.Paste")
			(net "M_F_CPU1_SB_DQ<9>")
		)
		(pad "114" smd rect
			(at -2.050034 37.824918 270)
			(size 0.519938 1.4986)
			(layers "F.Cu" "F.Mask" "F.Paste")
			(net "GND")
		)
		(pad "115" smd rect
			(at -2.050034 38.675056 270)
			(size 0.519938 1.4986)
			(layers "F.Cu" "F.Mask" "F.Paste")
			(net "M_F_CPU1_SB_DQS_DP<1>")
		)
		(pad "116" smd rect
			(at -2.050034 39.52494 270)
			(size 0.519938 1.4986)
			(layers "F.Cu" "F.Mask" "F.Paste")
			(net "M_F_CPU1_SB_DQS_DN<1>")
		)
		(pad "117" smd rect
			(at -2.050034 40.375078 270)
			(size 0.519938 1.4986)
			(layers "F.Cu" "F.Mask" "F.Paste")
			(net "GND")
		)
		(pad "118" smd rect
			(at -2.050034 41.224962 270)
			(size 0.519938 1.4986)
			(layers "F.Cu" "F.Mask" "F.Paste")
			(net "M_F_CPU1_SB_DQ<12>")
		)
		(pad "119" smd rect
			(at -2.050034 42.0751 270)
			(size 0.519938 1.4986)
			(layers "F.Cu" "F.Mask" "F.Paste")
			(net "GND")
		)
		(pad "120" smd rect
			(at -2.050034 42.924984 270)
			(size 0.519938 1.4986)
			(layers "F.Cu" "F.Mask" "F.Paste")
			(net "M_F_CPU1_SB_DQ<13>")
		)
		(pad "121" smd rect
			(at -2.050034 43.775122 270)
			(size 0.519938 1.4986)
			(layers "F.Cu" "F.Mask" "F.Paste")
			(net "GND")
		)
		(pad "122" smd rect
			(at -2.050034 44.625006 270)
			(size 0.519938 1.4986)
			(layers "F.Cu" "F.Mask" "F.Paste")
			(net "M_F_CPU1_SB_DQ<16>")
		)
		(pad "123" smd rect
			(at -2.050034 45.47489 270)
			(size 0.519938 1.4986)
			(layers "F.Cu" "F.Mask" "F.Paste")
			(net "GND")
		)
		(pad "124" smd rect
			(at -2.050034 46.325028 270)
			(size 0.519938 1.4986)
			(layers "F.Cu" "F.Mask" "F.Paste")
			(net "M_F_CPU1_SB_DQ<17>")
		)
		(pad "125" smd rect
			(at -2.050034 47.174912 270)
			(size 0.519938 1.4986)
			(layers "F.Cu" "F.Mask" "F.Paste")
			(net "GND")
		)
		(pad "126" smd rect
			(at -2.050034 48.02505 270)
			(size 0.519938 1.4986)
			(layers "F.Cu" "F.Mask" "F.Paste")
			(net "M_F_CPU1_SB_DQS_DP<2>")
		)
		(pad "127" smd rect
			(at -2.050034 48.874934 270)
			(size 0.519938 1.4986)
			(layers "F.Cu" "F.Mask" "F.Paste")
			(net "M_F_CPU1_SB_DQS_DN<2>")
		)
		(pad "128" smd rect
			(at -2.050034 49.725072 270)
			(size 0.519938 1.4986)
			(layers "F.Cu" "F.Mask" "F.Paste")
			(net "GND")
		)
		(pad "129" smd rect
			(at -2.050034 50.574956 270)
			(size 0.519938 1.4986)
			(layers "F.Cu" "F.Mask" "F.Paste")
			(net "M_F_CPU1_SB_DQ<20>")
		)
		(pad "130" smd rect
			(at -2.050034 51.425094 270)
			(size 0.519938 1.4986)
			(layers "F.Cu" "F.Mask" "F.Paste")
			(net "GND")
		)
		(pad "131" smd rect
			(at -2.050034 52.274978 270)
			(size 0.519938 1.4986)
			(layers "F.Cu" "F.Mask" "F.Paste")
			(net "M_F_CPU1_SB_DQ<21>")
		)
		(pad "132" smd rect
			(at -2.050034 53.125116 270)
			(size 0.519938 1.4986)
			(layers "F.Cu" "F.Mask" "F.Paste")
			(net "GND")
		)
		(pad "133" smd rect
			(at -2.050034 53.975 270)
			(size 0.519938 1.4986)
			(layers "F.Cu" "F.Mask" "F.Paste")
			(net "M_F_CPU1_SB_DQ<24>")
		)
		(pad "134" smd rect
			(at -2.050034 54.824884 270)
			(size 0.519938 1.4986)
			(layers "F.Cu" "F.Mask" "F.Paste")
			(net "GND")
		)
		(pad "135" smd rect
			(at -2.050034 55.675022 270)
			(size 0.519938 1.4986)
			(layers "F.Cu" "F.Mask" "F.Paste")
			(net "M_F_CPU1_SB_DQ<25>")
		)
		(pad "136" smd rect
			(at -2.050034 56.524906 270)
			(size 0.519938 1.4986)
			(layers "F.Cu" "F.Mask" "F.Paste")
			(net "GND")
		)
		(pad "137" smd rect
			(at -2.050034 57.375044 270)
			(size 0.519938 1.4986)
			(layers "F.Cu" "F.Mask" "F.Paste")
			(net "M_F_CPU1_SB_DQS_DP<3>")
		)
	)
)
